;LEADER: 12 
;HEADER: 
;CODE  : ASCII 
;FILE  : 9332_F0TG_MB_C_V02_0417_0820-bd-1-4.drl for backdrilling ... from layer TOP to layer GND1
;DESIGN: 9332_F0TG_MB_C_V02_0417_0820.brd
;MUST-NOT-CUT-LAYER = IN2,  MAX_DRILL_DEPTH = 19.85 MILS,  MFG_STUB_LENGTH = 0.00 MILS
;   BackdrillSize 1. = 17.000000 Tolerance = +0.000000/-0.000000 NON_PLATED MILS Quantity = 8
%
G90
X0307255Y1647150
X0297323Y1653772
X0307255Y1643750
X0297323Y1657172
X0747099Y0960966
X1723241Y0960965
X0150366Y0960966
X1126508Y0960965
M30
